FILE_TYPE = MULTI_PHYS_TABLE;

PART 'PI3PCIE3212ZBEX'

{========================================================================================}
:VALUE             | PART_TYPE | MATERIAL | PART_NUMBER    = STANDARD | LIFECYCLE          | PART_NUMBER   | JEDEC_TYPE             | DESCRIPTION                          | MANUFTR | MANUF_PN          | RD_CMPLS_LVL | CMPLS_LVL | FROM_PJ       | CLASS | DIP_SMD | DATA                     | EE_CHECK_LIST | FP_ECN | PSL | CREATOR | STATUS | CREATEDAY  ;
{========================================================================================}
 'PI3PCIE3212ZBEX' | 'SMLF'    | 'IC'     | 'AL003212003'(!) = ''       | ''               | 'AL003212003' |'QFN20_TH_0-5_2-5X4-5'| 'IC OTHER(20P) PI3PCIE3212ZBEX(QFN)' | 'PIM'   | 'PI3PCIE3212ZBEX' | 'EP(V1)'     | 'EP(V1)'  | 'IX5-PATRICK' | 'IC'  | ''      | 'PIM_PI3PCIE3212ZBX.pdf' | ''            | ''     | ''  | ''      | ''     | '20160201'
 'PI3PCIE3212ZBEX' | 'SMLF'    | 'EMPTY'  | 'AL003212003'(!) = ''       | ''               | 'AL003212003' |'QFN20_TH_0-5_2-5X4-5'| 'IC OTHER(20P) PI3PCIE3212ZBEX(QFN)' | 'PIM'   | 'PI3PCIE3212ZBEX' | 'EP(V1)'     | 'EP(V1)'  | 'IX5-PATRICK' | 'IC'  | ''      | 'PIM_PI3PCIE3212ZBX.pdf' | ''            | ''     | ''  | ''      | ''     | '20160201'

END_PART

END.

